(kicad_pcb
	(version 20260206)
	(generator "pcbnew")
	(generator_version "10.0")
	(general
		(thickness 1.6)
		(legacy_teardrops no)
	)
	(paper "A4")
	(title_block
		(title "Wiwynn_Tioga_Pass_MB.brd")
		(comment 1 "Tioga Pass / footprints 4212-4218 of 4770")
	)
	(layers
		(0 "F.Cu" signal "TOP")
		(4 "In1.Cu" signal "L2GND")
		(6 "In2.Cu" signal "L3")
		(8 "In3.Cu" signal "L4GND")
		(10 "In4.Cu" signal "L5")
		(12 "In5.Cu" signal "L6GND")
		(14 "In6.Cu" signal "L7VCC")
		(16 "In7.Cu" signal "L8VCC")
		(18 "In8.Cu" signal "L9GND")
		(20 "In9.Cu" signal "L10")
		(22 "In10.Cu" signal "L11GND")
		(24 "In11.Cu" signal "L12")
		(26 "In12.Cu" signal "L13GND")
		(2 "B.Cu" signal "BOTTOM")
		(9 "F.Adhes" user "F.Adhesive")
		(11 "B.Adhes" user "B.Adhesive")
		(13 "F.Paste" user "Package Geometry/Pastemask Top")
		(15 "B.Paste" user "Package Geometry/Pastemask Bottom")
		(5 "F.SilkS" user "Ref Des/Silkscreen Top")
		(7 "B.SilkS" user "Ref Des/Silkscreen Bottom")
		(1 "F.Mask" user "Board Geometry/Soldermask Top")
		(3 "B.Mask" user "Board Geometry/Soldermask Bottom")
		(17 "Dwgs.User" user "User.Drawings")
		(19 "Cmts.User" user "User.Comments")
		(21 "Eco1.User" user "User.Eco1")
		(23 "Eco2.User" user "User.Eco2")
		(25 "Edge.Cuts" user "Board Geometry/Outline")
		(27 "Margin" user)
		(31 "F.CrtYd" user "Package Geometry/Place Bound Top")
		(29 "B.CrtYd" user "Package Geometry/Place Bound Bottom")
		(35 "F.Fab" user "Ref Des/Assembly Top")
		(33 "B.Fab" user "Ref Des/Assembly Bottom")
	)
	(footprint ""
		(layer "B.Cu")
		(at 372.4275 -93.091 90)
		(property "Reference" "R3N16"
			(at 0 0 90)
			(layer "B.SilkS")
			(hide yes)
			(effects
				(font
					(size 1.27 1.27)
				)
				(justify mirror)
			)
		)
		(property "Value" ""
			(at 0 0 90)
			(layer "B.Fab")
			(effects
				(font
					(size 1.27 1.27)
				)
				(justify mirror)
			)
		)
		(duplicate_pad_numbers_are_jumpers no)
		(fp_poly
			(pts
				(xy 0.2794 -0.1016) (xy -0.2794 -0.1016) (xy -0.2794 0.9906) (xy 0.2794 0.9906)
			)
			(stroke
				(width 0)
				(type default)
			)
			(fill no)
			(layer "B.CrtYd")
		)
		(fp_line
			(start 0.2794 -0.1016)
			(end 0.2794 0.9906)
			(stroke
				(width 0.1)
				(type default)
			)
			(layer "B.Fab")
		)
		(fp_line
			(start -0.2794 -0.1016)
			(end 0.2794 -0.1016)
			(stroke
				(width 0.1)
				(type default)
			)
			(layer "B.Fab")
		)
		(fp_line
			(start 0.2794 0.9906)
			(end -0.2794 0.9906)
			(stroke
				(width 0.1)
				(type default)
			)
			(layer "B.Fab")
		)
		(fp_line
			(start -0.2794 0.9906)
			(end -0.2794 -0.1016)
			(stroke
				(width 0.1)
				(type default)
			)
			(layer "B.Fab")
		)
		(pad "1" smd rect
			(at 0 0 270)
			(size 0.508 0.508)
			(layers "B.Cu" "B.Mask" "B.Paste")
			(net "P1V05_PCH_STBY")
		)
		(pad "2" smd rect
			(at 0 0.889 270)
			(size 0.508 0.508)
			(layers "B.Cu" "B.Mask" "B.Paste")
			(net "FM_PRSNT_2_5_N")
		)
		(zone
			(layer "B.Cu")
			(hatch none 0.5)
			(connect_pads
				(clearance 0)
			)
			(min_thickness 0.25)
			(keepout
				(tracks allowed)
				(vias not_allowed)
				(pads allowed)
				(copperpour not_allowed)
				(footprints allowed)
			)
			(placement
				(enabled no)
				(sheetname "")
			)
			(fill
				(thermal_gap 0.5)
				(thermal_bridge_width 0.5)
				(island_removal_mode 0)
			)
			(polygon
				(pts
					(xy 372.6815 -93.345) (xy 372.6815 -92.837) (xy 373.0625 -92.837) (xy 373.0625 -93.345)
				)
			)
		)
		(zone
			(layer "B.Cu")
			(hatch none 0.5)
			(connect_pads
				(clearance 0)
			)
			(min_thickness 0.25)
			(keepout
				(tracks not_allowed)
				(vias allowed)
				(pads allowed)
				(copperpour not_allowed)
				(footprints allowed)
			)
			(placement
				(enabled no)
				(sheetname "")
			)
			(fill
				(thermal_gap 0.5)
				(thermal_bridge_width 0.5)
				(island_removal_mode 0)
			)
			(polygon
				(pts
					(xy 373.0625 -93.345) (xy 373.0625 -92.837) (xy 372.6815 -92.837) (xy 372.6815 -93.345)
				)
			)
		)
	)
	(footprint ""
		(layer "B.Cu")
		(at 390.1821 -64.443102 -90)
		(property "Reference" "R2T8"
			(at 0 0 90)
			(layer "B.SilkS")
			(hide yes)
			(effects
				(font
					(size 1.27 1.27)
				)
				(justify mirror)
			)
		)
		(property "Value" ""
			(at 0 0 90)
			(layer "B.Fab")
			(effects
				(font
					(size 1.27 1.27)
				)
				(justify mirror)
			)
		)
		(duplicate_pad_numbers_are_jumpers no)
		(fp_poly
			(pts
				(xy 0.2794 -0.1016) (xy -0.2794 -0.1016) (xy -0.2794 0.9906) (xy 0.2794 0.9906)
			)
			(stroke
				(width 0)
				(type default)
			)
			(fill no)
			(layer "B.CrtYd")
		)
		(fp_line
			(start -0.2794 0.9906)
			(end -0.2794 -0.1016)
			(stroke
				(width 0.1)
				(type default)
			)
			(layer "B.Fab")
		)
		(fp_line
			(start 0.2794 0.9906)
			(end -0.2794 0.9906)
			(stroke
				(width 0.1)
				(type default)
			)
			(layer "B.Fab")
		)
		(fp_line
			(start -0.2794 -0.1016)
			(end 0.2794 -0.1016)
			(stroke
				(width 0.1)
				(type default)
			)
			(layer "B.Fab")
		)
		(fp_line
			(start 0.2794 -0.1016)
			(end 0.2794 0.9906)
			(stroke
				(width 0.1)
				(type default)
			)
			(layer "B.Fab")
		)
		(pad "1" smd rect
			(at 0 0 90)
			(size 0.508 0.508)
			(layers "B.Cu" "B.Mask" "B.Paste")
			(net "P3V3_STBY")
		)
		(pad "2" smd rect
			(at 0 0.889 90)
			(size 0.508 0.508)
			(layers "B.Cu" "B.Mask" "B.Paste")
			(net "SPI_SWITCH_CS0_N")
		)
		(zone
			(layer "B.Cu")
			(hatch none 0.5)
			(connect_pads
				(clearance 0)
			)
			(min_thickness 0.25)
			(keepout
				(tracks not_allowed)
				(vias allowed)
				(pads allowed)
				(copperpour not_allowed)
				(footprints allowed)
			)
			(placement
				(enabled no)
				(sheetname "")
			)
			(fill
				(thermal_gap 0.5)
				(thermal_bridge_width 0.5)
				(island_removal_mode 0)
			)
			(polygon
				(pts
					(xy 389.5471 -64.189102) (xy 389.5471 -64.697102) (xy 389.9281 -64.697102) (xy 389.9281 -64.189102)
				)
			)
		)
		(zone
			(layer "B.Cu")
			(hatch none 0.5)
			(connect_pads
				(clearance 0)
			)
			(min_thickness 0.25)
			(keepout
				(tracks allowed)
				(vias not_allowed)
				(pads allowed)
				(copperpour not_allowed)
				(footprints allowed)
			)
			(placement
				(enabled no)
				(sheetname "")
			)
			(fill
				(thermal_gap 0.5)
				(thermal_bridge_width 0.5)
				(island_removal_mode 0)
			)
			(polygon
				(pts
					(xy 389.9281 -64.189102) (xy 389.9281 -64.697102) (xy 389.5471 -64.697102) (xy 389.5471 -64.189102)
				)
			)
		)
	)
	(footprint ""
		(layer "B.Cu")
		(at 181.5973 -4.4577)
		(property "Reference" "C6U12"
			(at 0 0 0)
			(layer "B.SilkS")
			(hide yes)
			(effects
				(font
					(size 1.27 1.27)
				)
				(justify mirror)
			)
		)
		(property "Value" ""
			(at 0 0 0)
			(layer "B.Fab")
			(effects
				(font
					(size 1.27 1.27)
				)
				(justify mirror)
			)
		)
		(duplicate_pad_numbers_are_jumpers no)
		(fp_poly
			(pts
				(xy 0.4953 -0.2032) (xy -0.4953 -0.2032) (xy -0.4953 1.6002) (xy 0.4953 1.6002)
			)
			(stroke
				(width 0)
				(type default)
			)
			(fill no)
			(layer "B.CrtYd")
		)
		(fp_line
			(start -0.4953 -0.2032)
			(end -0.4953 1.6002)
			(stroke
				(width 0.1)
				(type default)
			)
			(layer "B.Fab")
		)
		(fp_line
			(start -0.4953 1.6002)
			(end 0.4953 1.6002)
			(stroke
				(width 0.1)
				(type default)
			)
			(layer "B.Fab")
		)
		(fp_line
			(start 0.4953 -0.2032)
			(end -0.4953 -0.2032)
			(stroke
				(width 0.1)
				(type default)
			)
			(layer "B.Fab")
		)
		(fp_line
			(start 0.4953 1.6002)
			(end 0.4953 -0.2032)
			(stroke
				(width 0.1)
				(type default)
			)
			(layer "B.Fab")
		)
		(pad "1" smd rect
			(at 0 0 180)
			(size 0.762 0.889)
			(layers "B.Cu" "B.Mask" "B.Paste")
			(net "VSENSE_PVDDQ_ABC_VTT")
		)
		(pad "2" smd rect
			(at 0 1.397 180)
			(size 0.762 0.889)
			(layers "B.Cu" "B.Mask" "B.Paste")
			(net "GND")
		)
		(zone
			(layer "B.Cu")
			(hatch none 0.5)
			(connect_pads
				(clearance 0)
			)
			(min_thickness 0.25)
			(keepout
				(tracks not_allowed)
				(vias allowed)
				(pads allowed)
				(copperpour not_allowed)
				(footprints allowed)
			)
			(placement
				(enabled no)
				(sheetname "")
			)
			(fill
				(thermal_gap 0.5)
				(thermal_bridge_width 0.5)
				(island_removal_mode 0)
			)
			(polygon
				(pts
					(xy 181.9783 -4.0132) (xy 181.2163 -4.0132) (xy 181.2163 -3.5052) (xy 181.9783 -3.5052)
				)
			)
		)
	)
	(footprint ""
		(layer "B.Cu")
		(at 261.9248 -26.543 90)
		(property "Reference" "C5U12"
			(at -1.47828 0.78994 180)
			(unlocked yes)
			(layer "B.SilkS")
			(effects
				(font
					(size 0.4064 0.254)
					(thickness 0.1524)
				)
				(justify mirror)
			)
		)
		(property "Value" ""
			(at 0 0 90)
			(layer "B.Fab")
			(effects
				(font
					(size 1.27 1.27)
				)
				(justify mirror)
			)
		)
		(duplicate_pad_numbers_are_jumpers no)
		(fp_poly
			(pts
				(xy 0.7239 -0.2159) (xy -0.7239 -0.2159) (xy -0.7239 1.9939) (xy 0.7239 1.9939)
			)
			(stroke
				(width 0)
				(type default)
			)
			(fill no)
			(layer "B.CrtYd")
		)
		(fp_line
			(start 0.7239 -0.2159)
			(end 0.7239 1.9939)
			(stroke
				(width 0.1)
				(type default)
			)
			(layer "B.Fab")
		)
		(fp_line
			(start -0.7239 -0.2159)
			(end 0.7239 -0.2159)
			(stroke
				(width 0.1)
				(type default)
			)
			(layer "B.Fab")
		)
		(fp_line
			(start 0.7239 1.9939)
			(end -0.7239 1.9939)
			(stroke
				(width 0.1)
				(type default)
			)
			(layer "B.Fab")
		)
		(fp_line
			(start -0.7239 1.9939)
			(end -0.7239 -0.2159)
			(stroke
				(width 0.1)
				(type default)
			)
			(layer "B.Fab")
		)
		(pad "1" smd rect
			(at 0 0 270)
			(size 1.27 1.016)
			(layers "B.Cu" "B.Mask" "B.Paste")
			(net "PVTT_ABC")
		)
		(pad "2" smd rect
			(at 0 1.778 270)
			(size 1.27 1.016)
			(layers "B.Cu" "B.Mask" "B.Paste")
			(net "GND")
		)
		(zone
			(layer "B.Cu")
			(hatch none 0.5)
			(connect_pads
				(clearance 0)
			)
			(min_thickness 0.25)
			(keepout
				(tracks not_allowed)
				(vias allowed)
				(pads allowed)
				(copperpour not_allowed)
				(footprints allowed)
			)
			(placement
				(enabled no)
				(sheetname "")
			)
			(fill
				(thermal_gap 0.5)
				(thermal_bridge_width 0.5)
				(island_removal_mode 0)
			)
			(polygon
				(pts
					(xy 262.4328 -27.178) (xy 262.4328 -25.908) (xy 263.1948 -25.908) (xy 263.1948 -27.178)
				)
			)
		)
	)
	(footprint ""
		(layer "B.Cu")
		(at 173.863 -81.661 -90)
		(property "Reference" "C6P9"
			(at 0 0 90)
			(layer "B.SilkS")
			(hide yes)
			(effects
				(font
					(size 1.27 1.27)
				)
				(justify mirror)
			)
		)
		(property "Value" ""
			(at 0 0 90)
			(layer "B.Fab")
			(effects
				(font
					(size 1.27 1.27)
				)
				(justify mirror)
			)
		)
		(duplicate_pad_numbers_are_jumpers no)
		(fp_poly
			(pts
				(xy -0.3048 -0.1016) (xy -0.3048 0.9906) (xy 0.3048 0.9906) (xy 0.3048 -0.1016)
			)
			(stroke
				(width 0)
				(type default)
			)
			(fill no)
			(layer "B.CrtYd")
		)
		(fp_line
			(start -0.3048 0.9906)
			(end -0.3048 -0.1016)
			(stroke
				(width 0.1)
				(type default)
			)
			(layer "B.Fab")
		)
		(fp_line
			(start 0.3048 0.9906)
			(end -0.3048 0.9906)
			(stroke
				(width 0.1)
				(type default)
			)
			(layer "B.Fab")
		)
		(fp_line
			(start -0.3048 -0.1016)
			(end 0.3048 -0.1016)
			(stroke
				(width 0.1)
				(type default)
			)
			(layer "B.Fab")
		)
		(fp_line
			(start 0.3048 -0.1016)
			(end 0.3048 0.9906)
			(stroke
				(width 0.1)
				(type default)
			)
			(layer "B.Fab")
		)
		(pad "1" smd rect
			(at 0 0 90)
			(size 0.508 0.508)
			(layers "B.Cu" "B.Mask" "B.Paste")
			(net "P3V3_DB1200")
		)
		(pad "2" smd rect
			(at 0 0.889 90)
			(size 0.508 0.508)
			(layers "B.Cu" "B.Mask" "B.Paste")
			(net "GND")
		)
		(zone
			(layer "B.Cu")
			(hatch none 0.5)
			(connect_pads
				(clearance 0)
			)
			(min_thickness 0.25)
			(keepout
				(tracks not_allowed)
				(vias allowed)
				(pads allowed)
				(copperpour not_allowed)
				(footprints allowed)
			)
			(placement
				(enabled no)
				(sheetname "")
			)
			(fill
				(thermal_gap 0.5)
				(thermal_bridge_width 0.5)
				(island_removal_mode 0)
			)
			(polygon
				(pts
					(xy 173.228 -81.407) (xy 173.228 -81.915) (xy 173.609 -81.915) (xy 173.609 -81.407)
				)
			)
		)
		(zone
			(layer "B.Cu")
			(hatch none 0.5)
			(connect_pads
				(clearance 0)
			)
			(min_thickness 0.25)
			(keepout
				(tracks allowed)
				(vias not_allowed)
				(pads allowed)
				(copperpour not_allowed)
				(footprints allowed)
			)
			(placement
				(enabled no)
				(sheetname "")
			)
			(fill
				(thermal_gap 0.5)
				(thermal_bridge_width 0.5)
				(island_removal_mode 0)
			)
			(polygon
				(pts
					(xy 173.609 -81.407) (xy 173.609 -81.915) (xy 173.228 -81.915) (xy 173.228 -81.407)
				)
			)
		)
	)
	(footprint ""
		(layer "B.Cu")
		(at 110.007654 -73.51014)
		(property "Reference" "C7P14"
			(at 0 0 0)
			(layer "B.SilkS")
			(hide yes)
			(effects
				(font
					(size 1.27 1.27)
				)
				(justify mirror)
			)
		)
		(property "Value" ""
			(at 0 0 0)
			(layer "B.Fab")
			(effects
				(font
					(size 1.27 1.27)
				)
				(justify mirror)
			)
		)
		(duplicate_pad_numbers_are_jumpers no)
		(fp_poly
			(pts
				(xy 0.7239 -0.2159) (xy -0.7239 -0.2159) (xy -0.7239 1.9939) (xy 0.7239 1.9939)
			)
			(stroke
				(width 0)
				(type default)
			)
			(fill no)
			(layer "B.CrtYd")
		)
		(fp_line
			(start -0.7239 -0.2159)
			(end 0.7239 -0.2159)
			(stroke
				(width 0.1)
				(type default)
			)
			(layer "B.Fab")
		)
		(fp_line
			(start -0.7239 1.9939)
			(end -0.7239 -0.2159)
			(stroke
				(width 0.1)
				(type default)
			)
			(layer "B.Fab")
		)
		(fp_line
			(start 0.7239 -0.2159)
			(end 0.7239 1.9939)
			(stroke
				(width 0.1)
				(type default)
			)
			(layer "B.Fab")
		)
		(fp_line
			(start 0.7239 1.9939)
			(end -0.7239 1.9939)
			(stroke
				(width 0.1)
				(type default)
			)
			(layer "B.Fab")
		)
		(pad "1" smd rect
			(at 0 0 180)
			(size 1.27 1.016)
			(layers "B.Cu" "B.Mask" "B.Paste")
			(net "PVCCMCP_CPU1")
		)
		(pad "2" smd rect
			(at 0 1.778 180)
			(size 1.27 1.016)
			(layers "B.Cu" "B.Mask" "B.Paste")
			(net "GND")
		)
		(zone
			(layer "B.Cu")
			(hatch none 0.5)
			(connect_pads
				(clearance 0)
			)
			(min_thickness 0.25)
			(keepout
				(tracks not_allowed)
				(vias allowed)
				(pads allowed)
				(copperpour not_allowed)
				(footprints allowed)
			)
			(placement
				(enabled no)
				(sheetname "")
			)
			(fill
				(thermal_gap 0.5)
				(thermal_bridge_width 0.5)
				(island_removal_mode 0)
			)
			(polygon
				(pts
					(xy 110.642654 -73.00214) (xy 109.372654 -73.00214) (xy 109.372654 -72.24014) (xy 110.642654 -72.24014)
				)
			)
		)
	)
	(footprint ""
		(layer "B.Cu")
		(at 381.127 -82.423 90)
		(property "Reference" "U7W1"
			(at 0 0 90)
			(layer "B.SilkS")
			(hide yes)
			(effects
				(font
					(size 1.27 1.27)
				)
				(justify mirror)
			)
		)
		(property "Value" "*"
			(at 2.3622 -8.3185 90)
			(unlocked yes)
			(layer "B.Fab")
			(hide yes)
			(effects
				(font
					(size 1.27 1.016)
					(thickness 0.1524)
				)
				(justify mirror)
			)
		)
		(property "Device Type" "PI5A3157BC6E-GP_DISCRET-GC2-PIA"
			(at 2.3622 -10.2235 90)
			(unlocked yes)
			(layer "B.Fab")
			(hide yes)
			(effects
				(font
					(size 1.27 1.016)
					(thickness 0.1524)
				)
				(justify mirror)
			)
		)
		(duplicate_pad_numbers_are_jumpers no)
		(fp_line
			(start 1.4478 -1.7018)
			(end 1.4478 1.7018)
			(stroke
				(width 0.1524)
				(type default)
			)
			(layer "B.SilkS")
		)
		(fp_line
			(start -1.4478 -1.7018)
			(end 1.4478 -1.7018)
			(stroke
				(width 0.1524)
				(type default)
			)
			(layer "B.SilkS")
		)
		(fp_line
			(start 1.4478 1.7018)
			(end -1.4478 1.7018)
			(stroke
				(width 0.1524)
				(type default)
			)
			(layer "B.SilkS")
		)
		(fp_line
			(start -1.4478 1.7018)
			(end -1.4478 -1.7018)
			(stroke
				(width 0.1524)
				(type default)
			)
			(layer "B.SilkS")
		)
		(fp_line
			(start 1.5494 1.7907)
			(end 1.5494 0.8255)
			(stroke
				(width 0.3302)
				(type default)
			)
			(layer "B.SilkS")
		)
		(fp_line
			(start 0.5715 1.7907)
			(end 1.5494 1.7907)
			(stroke
				(width 0.3302)
				(type default)
			)
			(layer "B.SilkS")
		)
		(fp_poly
			(pts
				(xy 0.6604 1.7272) (xy 1.016 2.0828) (xy 0.3048 2.0828)
			)
			(stroke
				(width 0)
				(type default)
			)
			(fill yes)
			(layer "B.SilkS")
		)
		(fp_poly
			(pts
				(xy 1.524 -1.778) (xy -1.524 -1.778) (xy -1.524 1.778) (xy 1.524 1.778)
			)
			(stroke
				(width 0)
				(type default)
			)
			(fill no)
			(layer "B.CrtYd")
		)
		(fp_poly
			(pts
				(xy 1.524 -1.778) (xy -1.524 -1.778) (xy -1.524 1.778) (xy 1.524 1.778)
			)
			(stroke
				(width 0)
				(type default)
			)
			(fill no)
			(layer "B.Fab")
		)
		(pad "1" smd rect
			(at 0.65024 0.9398 270)
			(size 0.4064 1.016)
			(layers "B.Cu" "B.Mask" "B.Paste")
			(net "PECI_BMC")
		)
		(pad "2" smd rect
			(at 0 0.9398 270)
			(size 0.4064 1.016)
			(layers "B.Cu" "B.Mask" "B.Paste")
			(net "GND")
		)
		(pad "3" smd rect
			(at -0.65024 0.9398 270)
			(size 0.4064 1.016)
			(layers "B.Cu" "B.Mask" "B.Paste")
			(net "PECI_PCH")
		)
		(pad "4" smd rect
			(at -0.65024 -0.9398 270)
			(size 0.4064 1.016)
			(layers "B.Cu" "B.Mask" "B.Paste")
			(net "PECI_CPU_G")
		)
		(pad "5" smd rect
			(at 0 -0.9398 270)
			(size 0.4064 1.016)
			(layers "B.Cu" "B.Mask" "B.Paste")
			(net "P3V3_STBY")
		)
		(pad "6" smd rect
			(at 0.65024 -0.9398 270)
			(size 0.4064 1.016)
			(layers "B.Cu" "B.Mask" "B.Paste")
			(net "PECI_SEL")
		)
	)
)
